(kicad_pcb
	(version 20260206)
	(generator "pcbnew")
	(generator_version "10.0")
	(general
		(thickness 1.6)
		(legacy_teardrops no)
	)
	(paper "A4")
	(title_block
		(title "01162023_DA0F0TEBIF0_F0T_Expander_BD_F_brd_V02_OCP.brd")
		(comment 1 "Grand Teton / footprints 9145-9152 of 9728")
	)
	(layers
		(0 "F.Cu" signal "TOP")
		(4 "In1.Cu" signal "GND")
		(6 "In2.Cu" signal "VCC")
		(8 "In3.Cu" signal "VCC1")
		(10 "In4.Cu" signal "GND1")
		(12 "In5.Cu" signal "IN1")
		(14 "In6.Cu" signal "GND2")
		(16 "In7.Cu" signal "IN2")
		(18 "In8.Cu" signal "GND3")
		(20 "In9.Cu" signal "IN3")
		(22 "In10.Cu" signal "GND4")
		(24 "In11.Cu" signal "IN4")
		(26 "In12.Cu" signal "GND5")
		(28 "In13.Cu" signal "IN5")
		(30 "In14.Cu" signal "GND6")
		(32 "In15.Cu" signal "IN6")
		(34 "In16.Cu" signal "GND7")
		(2 "B.Cu" signal "BOTTOM")
		(9 "F.Adhes" user "F.Adhesive")
		(11 "B.Adhes" user "B.Adhesive")
		(13 "F.Paste" user "Package Geometry/Pastemask Top")
		(15 "B.Paste" user "Package Geometry/Pastemask Bottom")
		(5 "F.SilkS" user "Ref Des/Silkscreen Top")
		(7 "B.SilkS" user "Ref Des/Silkscreen Bottom")
		(1 "F.Mask" user "Board Geometry/Soldermask Top")
		(3 "B.Mask" user "Board Geometry/Soldermask Bottom")
		(17 "Dwgs.User" user "User.Drawings")
		(19 "Cmts.User" user "User.Comments")
		(21 "Eco1.User" user "User.Eco1")
		(23 "Eco2.User" user "User.Eco2")
		(25 "Edge.Cuts" user "Board Geometry/Outline")
		(27 "Margin" user)
		(31 "F.CrtYd" user "Package Geometry/Place Bound Top")
		(29 "B.CrtYd" user "Package Geometry/Place Bound Bottom")
		(35 "F.Fab" user "Ref Des/Assembly Top")
		(33 "B.Fab" user "Ref Des/Assembly Bottom")
	)
	(footprint ""
		(layer "B.Cu")
		(at 172.106844 -138.557 90)
		(property "Reference" "C901"
			(at 0 0 90)
			(layer "B.SilkS")
			(hide yes)
			(effects
				(font
					(size 1.27 1.27)
				)
				(justify mirror)
			)
		)
		(property "Value" ""
			(at 0 0 90)
			(layer "B.Fab")
			(effects
				(font
					(size 1.27 1.27)
				)
				(justify mirror)
			)
		)
		(duplicate_pad_numbers_are_jumpers no)
		(fp_line
			(start 0.7874 -0.4064)
			(end -0.7874 -0.4064)
			(stroke
				(width 0.1524)
				(type default)
			)
			(layer "B.SilkS")
		)
		(fp_line
			(start -0.7874 -0.4064)
			(end -0.7874 0.4064)
			(stroke
				(width 0.1524)
				(type default)
			)
			(layer "B.SilkS")
		)
		(fp_line
			(start 0.7874 0.4064)
			(end 0.7874 -0.4064)
			(stroke
				(width 0.1524)
				(type default)
			)
			(layer "B.SilkS")
		)
		(fp_line
			(start -0.7874 0.4064)
			(end 0.7874 0.4064)
			(stroke
				(width 0.1524)
				(type default)
			)
			(layer "B.SilkS")
		)
		(fp_line
			(start 0.67945 -0.305054)
			(end 0.12065 -0.305054)
			(stroke
				(width 0.1)
				(type default)
			)
			(layer "B.Fab")
		)
		(fp_line
			(start 0.12065 -0.305054)
			(end 0.12065 -0.2794)
			(stroke
				(width 0.1)
				(type default)
			)
			(layer "B.Fab")
		)
		(fp_line
			(start -0.12065 -0.3048)
			(end -0.67945 -0.3048)
			(stroke
				(width 0.1)
				(type default)
			)
			(layer "B.Fab")
		)
		(fp_line
			(start -0.67945 -0.3048)
			(end -0.67945 0.3048)
			(stroke
				(width 0.1)
				(type default)
			)
			(layer "B.Fab")
		)
		(fp_line
			(start 0.12065 -0.2794)
			(end -0.12065 -0.2794)
			(stroke
				(width 0.1)
				(type default)
			)
			(layer "B.Fab")
		)
		(fp_line
			(start -0.12065 -0.2794)
			(end -0.12065 -0.3048)
			(stroke
				(width 0.1)
				(type default)
			)
			(layer "B.Fab")
		)
		(fp_line
			(start 0.12065 0.2794)
			(end 0.12065 0.3048)
			(stroke
				(width 0.1)
				(type default)
			)
			(layer "B.Fab")
		)
		(fp_line
			(start -0.120396 0.2794)
			(end 0.12065 0.2794)
			(stroke
				(width 0.1)
				(type default)
			)
			(layer "B.Fab")
		)
		(fp_line
			(start 0.67945 0.3048)
			(end 0.67945 -0.305054)
			(stroke
				(width 0.1)
				(type default)
			)
			(layer "B.Fab")
		)
		(fp_line
			(start 0.12065 0.3048)
			(end 0.67945 0.3048)
			(stroke
				(width 0.1)
				(type default)
			)
			(layer "B.Fab")
		)
		(fp_line
			(start -0.120396 0.3048)
			(end -0.120396 0.2794)
			(stroke
				(width 0.1)
				(type default)
			)
			(layer "B.Fab")
		)
		(fp_line
			(start -0.67945 0.3048)
			(end -0.120396 0.3048)
			(stroke
				(width 0.1)
				(type default)
			)
			(layer "B.Fab")
		)
		(pad "1" smd circle
			(at 0.40005 0 270)
			(size 0 0)
			(layers "B.Cu" "B.Mask" "B.Paste")
			(net "P3V3_AUX")
		)
		(pad "2" smd circle
			(at -0.40005 0 270)
			(size 0 0)
			(layers "B.Cu" "B.Mask" "B.Paste")
			(net "GND")
		)
	)
	(footprint ""
		(layer "B.Cu")
		(at 175.267874 -286.18434 90)
		(property "Reference" "C3118"
			(at 0 0 90)
			(layer "B.SilkS")
			(hide yes)
			(effects
				(font
					(size 1.27 1.27)
				)
				(justify mirror)
			)
		)
		(property "Value" ""
			(at 0 0 90)
			(layer "B.Fab")
			(effects
				(font
					(size 1.27 1.27)
				)
				(justify mirror)
			)
		)
		(duplicate_pad_numbers_are_jumpers no)
		(fp_line
			(start 1.2954 -0.5842)
			(end -1.2954 -0.5842)
			(stroke
				(width 0.1524)
				(type default)
			)
			(layer "B.SilkS")
		)
		(fp_line
			(start -1.2954 -0.5842)
			(end -1.2954 0.5842)
			(stroke
				(width 0.1524)
				(type default)
			)
			(layer "B.SilkS")
		)
		(fp_line
			(start 1.2954 0.5842)
			(end 1.2954 -0.5842)
			(stroke
				(width 0.1524)
				(type default)
			)
			(layer "B.SilkS")
		)
		(fp_line
			(start -1.2954 0.5842)
			(end 1.2954 0.5842)
			(stroke
				(width 0.1524)
				(type default)
			)
			(layer "B.SilkS")
		)
		(fp_line
			(start 0.8636 -0.4572)
			(end -0.8636 -0.4572)
			(stroke
				(width 0.1)
				(type default)
			)
			(layer "B.Fab")
		)
		(fp_line
			(start -0.8636 -0.4572)
			(end -0.8636 -0.4064)
			(stroke
				(width 0.1)
				(type default)
			)
			(layer "B.Fab")
		)
		(fp_line
			(start 1.1938 -0.4064)
			(end 0.8636 -0.4064)
			(stroke
				(width 0.1)
				(type default)
			)
			(layer "B.Fab")
		)
		(fp_line
			(start 0.8636 -0.4064)
			(end 0.8636 -0.4572)
			(stroke
				(width 0.1)
				(type default)
			)
			(layer "B.Fab")
		)
		(fp_line
			(start -0.8636 -0.4064)
			(end -1.1938 -0.4064)
			(stroke
				(width 0.1)
				(type default)
			)
			(layer "B.Fab")
		)
		(fp_line
			(start -1.1938 -0.4064)
			(end -1.1938 0.4064)
			(stroke
				(width 0.1)
				(type default)
			)
			(layer "B.Fab")
		)
		(fp_line
			(start 1.1938 0.4064)
			(end 1.1938 -0.4064)
			(stroke
				(width 0.1)
				(type default)
			)
			(layer "B.Fab")
		)
		(fp_line
			(start 0.8636 0.4064)
			(end 1.1938 0.4064)
			(stroke
				(width 0.1)
				(type default)
			)
			(layer "B.Fab")
		)
		(fp_line
			(start -0.8636 0.4064)
			(end -0.8636 0.4572)
			(stroke
				(width 0.1)
				(type default)
			)
			(layer "B.Fab")
		)
		(fp_line
			(start -1.1938 0.4064)
			(end -0.8636 0.4064)
			(stroke
				(width 0.1)
				(type default)
			)
			(layer "B.Fab")
		)
		(fp_line
			(start 0.8636 0.4572)
			(end 0.8636 0.4064)
			(stroke
				(width 0.1)
				(type default)
			)
			(layer "B.Fab")
		)
		(fp_line
			(start -0.8636 0.4572)
			(end 0.8636 0.4572)
			(stroke
				(width 0.1)
				(type default)
			)
			(layer "B.Fab")
		)
		(pad "1" smd rect
			(at 0.7366 0)
			(size 0.7112 0.8128)
			(layers "B.Cu" "B.Mask" "B.Paste")
			(net "P1V25_SERDES_VDDPLL_PEX1")
		)
		(pad "2" smd rect
			(at -0.7366 0)
			(size 0.7112 0.8128)
			(layers "B.Cu" "B.Mask" "B.Paste")
			(net "GND")
		)
	)
	(footprint ""
		(layer "B.Cu")
		(at 298.499784 -299.699934 -90)
		(property "Reference" "C1684"
			(at 0 0 90)
			(layer "B.SilkS")
			(hide yes)
			(effects
				(font
					(size 1.27 1.27)
				)
				(justify mirror)
			)
		)
		(property "Value" ""
			(at 0 0 90)
			(layer "B.Fab")
			(effects
				(font
					(size 1.27 1.27)
				)
				(justify mirror)
			)
		)
		(duplicate_pad_numbers_are_jumpers no)
		(fp_line
			(start -0.299974 0.150114)
			(end 0.299974 0.150114)
			(stroke
				(width 0.1)
				(type default)
			)
			(layer "B.Fab")
		)
		(fp_line
			(start 0.299974 0.150114)
			(end 0.299974 -0.150114)
			(stroke
				(width 0.1)
				(type default)
			)
			(layer "B.Fab")
		)
		(fp_line
			(start -0.299974 -0.150114)
			(end -0.299974 0.150114)
			(stroke
				(width 0.1)
				(type default)
			)
			(layer "B.Fab")
		)
		(fp_line
			(start 0.299974 -0.150114)
			(end -0.299974 -0.150114)
			(stroke
				(width 0.1)
				(type default)
			)
			(layer "B.Fab")
		)
		(pad "1" smd rect
			(at 0.2667 0 90)
			(size 0.3048 0.381)
			(layers "B.Cu" "B.Mask" "B.Paste")
			(net "P0V8_SERDES_VDDA_PEX2")
		)
		(pad "2" smd rect
			(at -0.2667 0 90)
			(size 0.3048 0.381)
			(layers "B.Cu" "B.Mask" "B.Paste")
			(net "GND")
		)
	)
	(footprint ""
		(layer "B.Cu")
		(at 256.03327 -207.507078 180)
		(property "Reference" "R4299"
			(at 0 0 0)
			(layer "B.SilkS")
			(hide yes)
			(effects
				(font
					(size 1.27 1.27)
				)
				(justify mirror)
			)
		)
		(property "Value" ""
			(at 0 0 0)
			(layer "B.Fab")
			(effects
				(font
					(size 1.27 1.27)
				)
				(justify mirror)
			)
		)
		(duplicate_pad_numbers_are_jumpers no)
		(fp_line
			(start 0.7874 0.4064)
			(end 0.7874 -0.4064)
			(stroke
				(width 0.1524)
				(type default)
			)
			(layer "B.SilkS")
		)
		(fp_line
			(start 0.7874 -0.4064)
			(end -0.7874 -0.4064)
			(stroke
				(width 0.1524)
				(type default)
			)
			(layer "B.SilkS")
		)
		(fp_line
			(start -0.7874 0.4064)
			(end 0.7874 0.4064)
			(stroke
				(width 0.1524)
				(type default)
			)
			(layer "B.SilkS")
		)
		(fp_line
			(start -0.7874 -0.4064)
			(end -0.7874 0.4064)
			(stroke
				(width 0.1524)
				(type default)
			)
			(layer "B.SilkS")
		)
		(fp_line
			(start 0.67945 0.3048)
			(end 0.67945 -0.305054)
			(stroke
				(width 0.1)
				(type default)
			)
			(layer "B.Fab")
		)
		(fp_line
			(start 0.67945 -0.305054)
			(end 0.12065 -0.305054)
			(stroke
				(width 0.1)
				(type default)
			)
			(layer "B.Fab")
		)
		(fp_line
			(start 0.12065 0.3048)
			(end 0.67945 0.3048)
			(stroke
				(width 0.1)
				(type default)
			)
			(layer "B.Fab")
		)
		(fp_line
			(start 0.12065 0.2794)
			(end 0.12065 0.3048)
			(stroke
				(width 0.1)
				(type default)
			)
			(layer "B.Fab")
		)
		(fp_line
			(start 0.12065 -0.2794)
			(end -0.12065 -0.2794)
			(stroke
				(width 0.1)
				(type default)
			)
			(layer "B.Fab")
		)
		(fp_line
			(start 0.12065 -0.305054)
			(end 0.12065 -0.2794)
			(stroke
				(width 0.1)
				(type default)
			)
			(layer "B.Fab")
		)
		(fp_line
			(start -0.120396 0.3048)
			(end -0.120396 0.2794)
			(stroke
				(width 0.1)
				(type default)
			)
			(layer "B.Fab")
		)
		(fp_line
			(start -0.120396 0.2794)
			(end 0.12065 0.2794)
			(stroke
				(width 0.1)
				(type default)
			)
			(layer "B.Fab")
		)
		(fp_line
			(start -0.12065 -0.2794)
			(end -0.12065 -0.3048)
			(stroke
				(width 0.1)
				(type default)
			)
			(layer "B.Fab")
		)
		(fp_line
			(start -0.12065 -0.3048)
			(end -0.67945 -0.3048)
			(stroke
				(width 0.1)
				(type default)
			)
			(layer "B.Fab")
		)
		(fp_line
			(start -0.67945 0.3048)
			(end -0.120396 0.3048)
			(stroke
				(width 0.1)
				(type default)
			)
			(layer "B.Fab")
		)
		(fp_line
			(start -0.67945 -0.3048)
			(end -0.67945 0.3048)
			(stroke
				(width 0.1)
				(type default)
			)
			(layer "B.Fab")
		)
		(pad "1" smd circle
			(at 0.40005 0)
			(size 0 0)
			(layers "B.Cu" "B.Mask" "B.Paste")
			(net "JTAG_PLD_TDI")
		)
		(pad "2" smd circle
			(at -0.40005 0)
			(size 0 0)
			(layers "B.Cu" "B.Mask" "B.Paste")
			(net "JTAG_FPGA_TDI")
		)
	)
	(footprint ""
		(layer "B.Cu")
		(at 380.990602 -235.01096)
		(property "Reference" "C2583"
			(at 0 0 0)
			(layer "B.SilkS")
			(hide yes)
			(effects
				(font
					(size 1.27 1.27)
				)
				(justify mirror)
			)
		)
		(property "Value" ""
			(at 0 0 0)
			(layer "B.Fab")
			(effects
				(font
					(size 1.27 1.27)
				)
				(justify mirror)
			)
		)
		(duplicate_pad_numbers_are_jumpers no)
		(fp_line
			(start -1.2954 -0.5842)
			(end -1.2954 0.5842)
			(stroke
				(width 0.1524)
				(type default)
			)
			(layer "B.SilkS")
		)
		(fp_line
			(start -1.2954 0.5842)
			(end 1.2954 0.5842)
			(stroke
				(width 0.1524)
				(type default)
			)
			(layer "B.SilkS")
		)
		(fp_line
			(start 1.2954 -0.5842)
			(end -1.2954 -0.5842)
			(stroke
				(width 0.1524)
				(type default)
			)
			(layer "B.SilkS")
		)
		(fp_line
			(start 1.2954 0.5842)
			(end 1.2954 -0.5842)
			(stroke
				(width 0.1524)
				(type default)
			)
			(layer "B.SilkS")
		)
		(fp_line
			(start -1.1938 -0.4064)
			(end -1.1938 0.4064)
			(stroke
				(width 0.1)
				(type default)
			)
			(layer "B.Fab")
		)
		(fp_line
			(start -1.1938 0.4064)
			(end -0.8636 0.4064)
			(stroke
				(width 0.1)
				(type default)
			)
			(layer "B.Fab")
		)
		(fp_line
			(start -0.8636 -0.4572)
			(end -0.8636 -0.4064)
			(stroke
				(width 0.1)
				(type default)
			)
			(layer "B.Fab")
		)
		(fp_line
			(start -0.8636 -0.4064)
			(end -1.1938 -0.4064)
			(stroke
				(width 0.1)
				(type default)
			)
			(layer "B.Fab")
		)
		(fp_line
			(start -0.8636 0.4064)
			(end -0.8636 0.4572)
			(stroke
				(width 0.1)
				(type default)
			)
			(layer "B.Fab")
		)
		(fp_line
			(start -0.8636 0.4572)
			(end 0.8636 0.4572)
			(stroke
				(width 0.1)
				(type default)
			)
			(layer "B.Fab")
		)
		(fp_line
			(start 0.8636 -0.4572)
			(end -0.8636 -0.4572)
			(stroke
				(width 0.1)
				(type default)
			)
			(layer "B.Fab")
		)
		(fp_line
			(start 0.8636 -0.4064)
			(end 0.8636 -0.4572)
			(stroke
				(width 0.1)
				(type default)
			)
			(layer "B.Fab")
		)
		(fp_line
			(start 0.8636 0.4064)
			(end 1.1938 0.4064)
			(stroke
				(width 0.1)
				(type default)
			)
			(layer "B.Fab")
		)
		(fp_line
			(start 0.8636 0.4572)
			(end 0.8636 0.4064)
			(stroke
				(width 0.1)
				(type default)
			)
			(layer "B.Fab")
		)
		(fp_line
			(start 1.1938 -0.4064)
			(end 0.8636 -0.4064)
			(stroke
				(width 0.1)
				(type default)
			)
			(layer "B.Fab")
		)
		(fp_line
			(start 1.1938 0.4064)
			(end 1.1938 -0.4064)
			(stroke
				(width 0.1)
				(type default)
			)
			(layer "B.Fab")
		)
		(pad "1" smd rect
			(at 0.7366 0 270)
			(size 0.7112 0.8128)
			(layers "B.Cu" "B.Mask" "B.Paste")
			(net "P3V3_SDB_VPHY")
		)
		(pad "2" smd rect
			(at -0.7366 0 270)
			(size 0.7112 0.8128)
			(layers "B.Cu" "B.Mask" "B.Paste")
			(net "GND")
		)
	)
	(footprint ""
		(layer "B.Cu")
		(at 421.249856 -296.8498 180)
		(property "Reference" "C3468"
			(at 0 0 0)
			(layer "B.SilkS")
			(hide yes)
			(effects
				(font
					(size 1.27 1.27)
				)
				(justify mirror)
			)
		)
		(property "Value" ""
			(at 0 0 0)
			(layer "B.Fab")
			(effects
				(font
					(size 1.27 1.27)
				)
				(justify mirror)
			)
		)
		(duplicate_pad_numbers_are_jumpers no)
		(fp_line
			(start 0.299974 0.150114)
			(end 0.299974 -0.150114)
			(stroke
				(width 0.1)
				(type default)
			)
			(layer "B.Fab")
		)
		(fp_line
			(start 0.299974 -0.150114)
			(end -0.299974 -0.150114)
			(stroke
				(width 0.1)
				(type default)
			)
			(layer "B.Fab")
		)
		(fp_line
			(start -0.299974 0.150114)
			(end 0.299974 0.150114)
			(stroke
				(width 0.1)
				(type default)
			)
			(layer "B.Fab")
		)
		(fp_line
			(start -0.299974 -0.150114)
			(end -0.299974 0.150114)
			(stroke
				(width 0.1)
				(type default)
			)
			(layer "B.Fab")
		)
		(pad "1" smd rect
			(at 0.2667 0)
			(size 0.3048 0.381)
			(layers "B.Cu" "B.Mask" "B.Paste")
			(net "P1V25_SERDES_VDDPLL_PEX3")
		)
		(pad "2" smd rect
			(at -0.2667 0)
			(size 0.3048 0.381)
			(layers "B.Cu" "B.Mask" "B.Paste")
			(net "GND")
		)
	)
	(footprint ""
		(layer "B.Cu")
		(at 416.499802 -293.52494 180)
		(property "Reference" "C1868"
			(at 0 0 0)
			(layer "B.SilkS")
			(hide yes)
			(effects
				(font
					(size 1.27 1.27)
				)
				(justify mirror)
			)
		)
		(property "Value" ""
			(at 0 0 0)
			(layer "B.Fab")
			(effects
				(font
					(size 1.27 1.27)
				)
				(justify mirror)
			)
		)
		(duplicate_pad_numbers_are_jumpers no)
		(fp_line
			(start 0.299974 0.150114)
			(end 0.299974 -0.150114)
			(stroke
				(width 0.1)
				(type default)
			)
			(layer "B.Fab")
		)
		(fp_line
			(start 0.299974 -0.150114)
			(end -0.299974 -0.150114)
			(stroke
				(width 0.1)
				(type default)
			)
			(layer "B.Fab")
		)
		(fp_line
			(start -0.299974 0.150114)
			(end 0.299974 0.150114)
			(stroke
				(width 0.1)
				(type default)
			)
			(layer "B.Fab")
		)
		(fp_line
			(start -0.299974 -0.150114)
			(end -0.299974 0.150114)
			(stroke
				(width 0.1)
				(type default)
			)
			(layer "B.Fab")
		)
		(pad "1" smd rect
			(at 0.2667 0)
			(size 0.3048 0.381)
			(layers "B.Cu" "B.Mask" "B.Paste")
			(net "P0V8_PEX3")
		)
		(pad "2" smd rect
			(at -0.2667 0)
			(size 0.3048 0.381)
			(layers "B.Cu" "B.Mask" "B.Paste")
			(net "GND")
		)
	)
	(footprint ""
		(layer "B.Cu")
		(at 128.095248 -173.095412)
		(property "Reference" "L11"
			(at 0 0 0)
			(layer "B.SilkS")
			(hide yes)
			(effects
				(font
					(size 1.27 1.27)
				)
				(justify mirror)
			)
		)
		(property "Value" ""
			(at 0 0 0)
			(layer "B.Fab")
			(effects
				(font
					(size 1.27 1.27)
				)
				(justify mirror)
			)
		)
		(duplicate_pad_numbers_are_jumpers no)
		(fp_line
			(start -1.27 0.5842)
			(end -1.27 -0.5842)
			(stroke
				(width 0.1524)
				(type default)
			)
			(layer "B.SilkS")
		)
		(fp_line
			(start -1.27 0.5842)
			(end 1.27 0.5842)
			(stroke
				(width 0.1524)
				(type default)
			)
			(layer "B.SilkS")
		)
		(fp_line
			(start 1.27 -0.5842)
			(end -1.27 -0.5842)
			(stroke
				(width 0.1524)
				(type default)
			)
			(layer "B.SilkS")
		)
		(fp_line
			(start 1.27 -0.5588)
			(end 1.27 -0.5842)
			(stroke
				(width 0.1524)
				(type default)
			)
			(layer "B.SilkS")
		)
		(fp_line
			(start 1.27 0.5842)
			(end 1.27 -0.5842)
			(stroke
				(width 0.1524)
				(type default)
			)
			(layer "B.SilkS")
		)
		(fp_line
			(start -1.1938 -0.406654)
			(end -1.1938 0.4064)
			(stroke
				(width 0.1)
				(type default)
			)
			(layer "B.Fab")
		)
		(fp_line
			(start -1.1938 0.4064)
			(end -0.9144 0.4064)
			(stroke
				(width 0.1)
				(type default)
			)
			(layer "B.Fab")
		)
		(fp_line
			(start -0.9144 -0.508)
			(end -0.9144 -0.406654)
			(stroke
				(width 0.1)
				(type default)
			)
			(layer "B.Fab")
		)
		(fp_line
			(start -0.9144 -0.406654)
			(end -1.1938 -0.406654)
			(stroke
				(width 0.1)
				(type default)
			)
			(layer "B.Fab")
		)
		(fp_line
			(start -0.9144 0.4064)
			(end -0.9144 0.508)
			(stroke
				(width 0.1)
				(type default)
			)
			(layer "B.Fab")
		)
		(fp_line
			(start -0.9144 0.508)
			(end 0.9144 0.508)
			(stroke
				(width 0.1)
				(type default)
			)
			(layer "B.Fab")
		)
		(fp_line
			(start 0.9144 -0.508)
			(end -0.9144 -0.508)
			(stroke
				(width 0.1)
				(type default)
			)
			(layer "B.Fab")
		)
		(fp_line
			(start 0.9144 -0.406654)
			(end 0.9144 -0.508)
			(stroke
				(width 0.1)
				(type default)
			)
			(layer "B.Fab")
		)
		(fp_line
			(start 0.9144 0.406654)
			(end 1.194308 0.406654)
			(stroke
				(width 0.1)
				(type default)
			)
			(layer "B.Fab")
		)
		(fp_line
			(start 0.9144 0.508)
			(end 0.9144 0.406654)
			(stroke
				(width 0.1)
				(type default)
			)
			(layer "B.Fab")
		)
		(fp_line
			(start 1.194308 -0.406654)
			(end 0.9144 -0.406654)
			(stroke
				(width 0.1)
				(type default)
			)
			(layer "B.Fab")
		)
		(fp_line
			(start 1.194308 0.406654)
			(end 1.194308 -0.406654)
			(stroke
				(width 0.1)
				(type default)
			)
			(layer "B.Fab")
		)
		(pad "1" smd rect
			(at 0.7366 0 270)
			(size 0.7112 0.8128)
			(layers "B.Cu" "B.Mask" "B.Paste")
			(net "P3V3")
		)
		(pad "2" smd rect
			(at -0.7366 0 270)
			(size 0.7112 0.8128)
			(layers "B.Cu" "B.Mask" "B.Paste")
			(net "P3V3_DB2000QL_FB_VDD")
		)
	)
)
